#ISCELL
  pure_quanta quanta_title_block_c *
  *
#CELL
  pure_quanta q_res *
  page117_i10
#ISCELL
  standard offpage *
  page117_i11
#ISCELL
  standard offpage *
  page117_i12
#CELL
  pure_quanta q_res *
  page117_i13
#ISCELL
  logical_power universal_power *
  page117_i14
#ISCELL
  logical_power universal_power *
  page117_i15
#CELL
  pure_quanta q_res *
  page117_i16
#CELL
  pure_quanta q_res *
  page117_i17
#ISCELL
  logical_power universal_gnd *
  page117_i18
#CELL
  pure_quanta q_res *
  page117_i19
#ISCELL
  logical_power universal_gnd *
  page117_i20
#ISCELL
  standard offpage *
  page117_i6
#ISCELL
  standard offpage *
  page117_i7
#CELL
  pure_quanta q_res *
  page117_i9
